FILE_TYPE = MACRO_DRAWING;
SET COLOR_WIRE YELLOW;
SET COLOR_PROP MONO;
SET COLOR_DOT WHITE;
SET COLOR_ARC YELLOW;
SET COLOR_BODY GREEN;
SET COLOR_NOTE MONO;
SET PROP_DISPLAY VALUE;
SET PAGE_NUMBER P184;
FORCEADD OFFPAGE..3
(-1750 -3425);
FORCEPROP 2 LAST $XR1 119 
J 0
(-1416 -3425);
DISPLAY 0.638298 (-1416 -3425);
PAINT MONO (-1416 -3425);
FORCEPROP 2 LAST $XR0 133 
J 0
(-1536 -3425);
DISPLAY 0.638298 (-1536 -3425);
PAINT MONO (-1536 -3425);
FORCEPROP 2 LAST CDS_LIB mstr_standard
J 0
(-1750 -3425);
PAINT ORANGE (-1750 -3425);
DISPLAY INVISIBLE (-1750 -3425);
FORCEPROP 2 LAST PATH I100
J 0
(-1525 -3375);
DISPLAY 1.021277 (-1525 -3375);
PAINT ORANGE (-1525 -3375);
DISPLAY INVISIBLE (-1525 -3375);
FORCEPROP 1 LAST OFFPAGE TRUE
J 0
(-1425 -3550);
DISPLAY 0.872340 (-1425 -3550);
PAINT GREEN (-1425 -3550);
DISPLAY INVISIBLE (-1425 -3550);
FORCEPROP 1 LAST COMMENT_BODY TRUE
J 0
(-1800 -3525);
DISPLAY 0.872340 (-1800 -3525);
PAINT GREEN (-1800 -3525);
DISPLAY INVISIBLE (-1800 -3525);
FORCEADD GND..1
R 2
(-3225 -3900);
FORCEPROP 3 LASTPIN (-3225 -3850) SIG_NAME GND\g
J 0
(-3215 -3840);
DISPLAY 0.659574 (-3215 -3840);
PAINT MONO (-3215 -3840);
DISPLAY INVISIBLE (-3215 -3840);
FORCEPROP 1 LAST VOLTAGE 0
J 0
(-3225 -3900);
PAINT SKYBLUE (-3225 -3900);
DISPLAY INVISIBLE (-3225 -3900);
FORCEPROP 2 LAST BOM_COST MEM
J 0
(-3225 -3895);
PAINT ORANGE (-3225 -3895);
DISPLAY INVISIBLE (-3225 -3895);
FORCEPROP 1 LAST SIZE 1B
J 2
(-3300 -3950);
DISPLAY 1.170213 (-3300 -3950);
PAINT GREEN (-3300 -3950);
DISPLAY INVISIBLE (-3300 -3950);
FORCEPROP 2 LAST CDS_LIB mstr_symbols
J 0
(-3225 -3900);
PAINT MONO (-3225 -3900);
DISPLAY INVISIBLE (-3225 -3900);
FORCEPROP 1 LAST PATH I101
J 2
(-3300 -3900);
DISPLAY 0.872340 (-3300 -3900);
PAINT AQUA (-3300 -3900);
DISPLAY INVISIBLE (-3300 -3900);
FORCEPROP 2 LAST ROOM DDR4_CH_G
J 0
(-3225 -3895);
PAINT ORANGE (-3225 -3895);
DISPLAY INVISIBLE (-3225 -3895);
FORCEPROP 1 LAST BODY_TYPE PLUMBING
J 2
(-3180 -3943);
DISPLAY 0.340426 (-3180 -3943);
PAINT GREEN (-3180 -3943);
DISPLAY INVISIBLE (-3180 -3943);
FORCEPROP 1 LAST HDL_POWER GND
J 2
(-3225 -3750);
DISPLAY 0.553191 (-3225 -3750);
PAINT GREEN (-3225 -3750);
DISPLAY INVISIBLE (-3225 -3750);
FORCEADD OFFPAGE..6
(-5300 -3675);
FORCEPROP 2 LAST $XR0 167 
J 0
(-5580 -3675);
DISPLAY 0.638298 (-5580 -3675);
PAINT MONO (-5580 -3675);
FORCEPROP 2 LAST $XR1 191 
J 0
(-5700 -3675);
DISPLAY 0.638298 (-5700 -3675);
PAINT MONO (-5700 -3675);
FORCEPROP 2 LAST CDS_LIB mstr_standard
J 0
(-5300 -3675);
PAINT MONO (-5300 -3675);
DISPLAY INVISIBLE (-5300 -3675);
FORCEPROP 2 LAST PATH I102
J 0
(-5250 -3600);
DISPLAY 1.021277 (-5250 -3600);
PAINT ORANGE (-5250 -3600);
DISPLAY INVISIBLE (-5250 -3600);
FORCEPROP 1 LAST OFFPAGE TRUE
J 0
(-4975 -3800);
DISPLAY 0.872340 (-4975 -3800);
PAINT GREEN (-4975 -3800);
DISPLAY INVISIBLE (-4975 -3800);
FORCEPROP 1 LAST COMMENT_BODY TRUE
J 0
(-5200 -3750);
DISPLAY 0.872340 (-5200 -3750);
PAINT GREEN (-5200 -3750);
DISPLAY INVISIBLE (-5200 -3750);
FORCEADD OFFPAGE..4
(-1750 -3525);
FORCEPROP 2 LAST $XR1 191 
J 0
(-1444 -3525);
DISPLAY 0.638298 (-1444 -3525);
PAINT MONO (-1444 -3525);
FORCEPROP 2 LAST $XR0 167 
J 0
(-1564 -3525);
DISPLAY 0.638298 (-1564 -3525);
PAINT MONO (-1564 -3525);
FORCEPROP 2 LAST CDS_LIB mstr_standard
J 0
(-1750 -3525);
PAINT MONO (-1750 -3525);
DISPLAY INVISIBLE (-1750 -3525);
FORCEPROP 2 LAST PATH I103
J 0
(-1700 -3450);
DISPLAY 1.021277 (-1700 -3450);
PAINT ORANGE (-1700 -3450);
DISPLAY INVISIBLE (-1700 -3450);
FORCEPROP 1 LAST OFFPAGE TRUE
J 0
(-1425 -3650);
DISPLAY 0.872340 (-1425 -3650);
PAINT GREEN (-1425 -3650);
DISPLAY INVISIBLE (-1425 -3650);
FORCEPROP 1 LAST COMMENT_BODY TRUE
J 0
(-1775 -3625);
DISPLAY 0.872340 (-1775 -3625);
PAINT GREEN (-1775 -3625);
DISPLAY INVISIBLE (-1775 -3625);
FORCEADD STANDOFF..2
(-5125 -1900);
FORCEPROP 1 LAST LOCATION RM8D1
J 0
(-5224 -1650);
DISPLAY 0.617021 (-5224 -1650);
PAINT AQUA (-5224 -1650);
FORCEPROP 1 LAST PART_NUMBER H72821-001
J 0
(-5224 -2047);
DISPLAY 0.617021 (-5224 -2047);
PAINT BLUE (-5224 -2047);
FORCEPROP 1 LAST MATERIAL SO
J 0
(-5224 -1701);
DISPLAY 0.617021 (-5224 -1701);
PAINT SKYBLUE (-5224 -1701);
FORCEPROP 2 LASTPIN (-4975 -1900) $PN 1
J 0
(-4965 -1890);
DISPLAY 0.617021 (-4965 -1890);
PAINT ORANGE (-4965 -1890);
FORCEPROP 1 LAST PACK_TYPE TH1
J 0
(-5224 -1599);
PAINT SKYBLUE (-5224 -1599);
DISPLAY INVISIBLE (-5224 -1599);
FORCEPROP 2 LAST CDS_LOCATION RM8D1
J 0
(-5224 -1650);
DISPLAY 0.617021 (-5224 -1650);
PAINT AQUA (-5224 -1650);
DISPLAY INVISIBLE (-5224 -1650);
FORCEPROP 2 LAST SEC 1
J 0
(-5200 -1600);
DISPLAY 0.680851 (-5200 -1600);
PAINT MONO (-5200 -1600);
DISPLAY INVISIBLE (-5200 -1600);
FORCEPROP 2 LAST SEC_TYPE TH1
J 0
(-5200 -1600);
DISPLAY 1.021277 (-5200 -1600);
PAINT ORANGE (-5200 -1600);
DISPLAY INVISIBLE (-5200 -1600);
FORCEPROP 2 LAST CDS_LIB mstr_misc
J 0
(-5125 -1900);
PAINT ORANGE (-5125 -1900);
DISPLAY INVISIBLE (-5125 -1900);
FORCEPROP 1 LAST PATH I104
J 0
(-4950 -1701);
PAINT GREEN (-4950 -1701);
DISPLAY INVISIBLE (-4950 -1701);
FORCEADD GND..1
(-4850 -2125);
FORCEPROP 3 LASTPIN (-4850 -2075) SIG_NAME GND\g
J 0
(-4840 -2065);
DISPLAY 0.659574 (-4840 -2065);
PAINT MONO (-4840 -2065);
DISPLAY INVISIBLE (-4840 -2065);
FORCEPROP 1 LAST VOLTAGE 0.0V
J 0
(-4895 -2168);
DISPLAY 0.340426 (-4895 -2168);
PAINT SKYBLUE (-4895 -2168);
DISPLAY INVISIBLE (-4895 -2168);
FORCEPROP 1 LAST SIZE 1B
J 0
(-4775 -2175);
DISPLAY 0.872340 (-4775 -2175);
PAINT AQUA (-4775 -2175);
DISPLAY INVISIBLE (-4775 -2175);
FORCEPROP 2 LAST CDS_LIB mstr_symbols
J 0
(-4850 -2125);
PAINT ORANGE (-4850 -2125);
DISPLAY INVISIBLE (-4850 -2125);
FORCEPROP 1 LAST PATH I105
J 0
(-4775 -2125);
DISPLAY 0.872340 (-4775 -2125);
PAINT AQUA (-4775 -2125);
DISPLAY INVISIBLE (-4775 -2125);
FORCEPROP 1 LAST BODY_TYPE PLUMBING
J 0
(-4895 -2168);
DISPLAY 0.340426 (-4895 -2168);
PAINT GREEN (-4895 -2168);
DISPLAY INVISIBLE (-4895 -2168);
FORCEPROP 1 LAST HDL_POWER GND
J 0
(-4850 -1975);
DISPLAY 0.872340 (-4850 -1975);
PAINT GREEN (-4850 -1975);
DISPLAY INVISIBLE (-4850 -1975);
FORCEADD SCONN11_H67026001..1
(-3700 -3375);
FORCEPROP 1 LAST LOCATION J8E1
J 0
(-4000 -2825);
DISPLAY 0.617021 (-4000 -2825);
PAINT AQUA (-4000 -2825);
FORCEPROP 1 LAST PART_NUMBER H67026-001
J 0
(-4000 -3875);
DISPLAY 0.617021 (-4000 -3875);
PAINT BLUE (-4000 -3875);
FORCEPROP 1 LAST MATERIAL CONN
J 0
(-4000 -2875);
DISPLAY 0.617021 (-4000 -2875);
PAINT SKYBLUE (-4000 -2875);
FORCEPROP 2 LASTPIN (-4050 -3175) $PN 1
J 2
(-4060 -3165);
DISPLAY 0.617021 (-4060 -3165);
PAINT ORANGE (-4060 -3165);
FORCEPROP 2 LASTPIN (-4050 -3275) $PN 2
J 2
(-4060 -3265);
DISPLAY 0.617021 (-4060 -3265);
PAINT ORANGE (-4060 -3265);
FORCEPROP 2 LASTPIN (-4050 -3375) $PN 3
J 2
(-4060 -3365);
DISPLAY 0.617021 (-4060 -3365);
PAINT ORANGE (-4060 -3365);
FORCEPROP 2 LASTPIN (-4050 -3475) $PN 4
J 2
(-4060 -3465);
DISPLAY 0.617021 (-4060 -3465);
PAINT ORANGE (-4060 -3465);
FORCEPROP 2 LASTPIN (-4050 -3575) $PN 5
J 2
(-4060 -3565);
DISPLAY 0.617021 (-4060 -3565);
PAINT ORANGE (-4060 -3565);
FORCEPROP 2 LASTPIN (-4050 -3675) $PN 6
J 2
(-4060 -3665);
DISPLAY 0.617021 (-4060 -3665);
PAINT ORANGE (-4060 -3665);
FORCEPROP 2 LASTPIN (-3350 -3225) $PN 7
J 0
(-3340 -3215);
DISPLAY 0.617021 (-3340 -3215);
PAINT ORANGE (-3340 -3215);
FORCEPROP 2 LASTPIN (-3350 -3325) $PN 8
J 0
(-3340 -3315);
DISPLAY 0.617021 (-3340 -3315);
PAINT ORANGE (-3340 -3315);
FORCEPROP 2 LASTPIN (-3350 -3425) $PN 9
J 0
(-3340 -3415);
DISPLAY 0.617021 (-3340 -3415);
PAINT ORANGE (-3340 -3415);
FORCEPROP 2 LASTPIN (-3350 -3525) $PN 10
J 0
(-3340 -3515);
DISPLAY 0.617021 (-3340 -3515);
PAINT ORANGE (-3340 -3515);
FORCEPROP 2 LASTPIN (-3350 -3625) $PN 11
J 0
(-3340 -3615);
DISPLAY 0.617021 (-3340 -3615);
PAINT ORANGE (-3340 -3615);
FORCEPROP 2 LASTPIN (-3350 -3125) $PN MP1
J 0
(-3340 -3115);
DISPLAY 0.617021 (-3340 -3115);
PAINT ORANGE (-3340 -3115);
FORCEPROP 2 LASTPIN (-3350 -3725) $PN MP2
J 0
(-3340 -3715);
DISPLAY 0.617021 (-3340 -3715);
PAINT ORANGE (-3340 -3715);
FORCEPROP 1 LAST PACK_TYPE SM
J 0
(-4000 -2775);
PAINT SKYBLUE (-4000 -2775);
DISPLAY INVISIBLE (-4000 -2775);
FORCEPROP 2 LAST CDS_LOCATION J8E1
J 0
(-4000 -2825);
DISPLAY 0.617021 (-4000 -2825);
PAINT AQUA (-4000 -2825);
DISPLAY INVISIBLE (-4000 -2825);
FORCEPROP 2 LAST SEC 1
J 0
(-4000 -2775);
DISPLAY 0.680851 (-4000 -2775);
PAINT MONO (-4000 -2775);
DISPLAY INVISIBLE (-4000 -2775);
FORCEPROP 2 LAST SEC_TYPE SM
J 0
(-4000 -2775);
DISPLAY 1.021277 (-4000 -2775);
PAINT ORANGE (-4000 -2775);
DISPLAY INVISIBLE (-4000 -2775);
FORCEPROP 2 LAST CDS_LIB mstr_sconn
J 0
(-3700 -3375);
PAINT MONO (-3700 -3375);
DISPLAY INVISIBLE (-3700 -3375);
FORCEPROP 1 LAST CDS_LMAN_SYM_OUTLINE -300,450,300,-450
J 0
(-3700 -3375);
DISPLAY 0.468085 (-3700 -3375);
PAINT GREEN (-3700 -3375);
DISPLAY INVISIBLE (-3700 -3375);
FORCEPROP 0 LAST BOM_COST MIO_SECURITY
J 0
(-4000 -2725);
DISPLAY 1.021277 (-4000 -2725);
PAINT ORANGE (-4000 -2725);
DISPLAY INVISIBLE (-4000 -2725);
FORCEPROP 1 LAST PATH I87
J 0
(-3600 -2874);
PAINT GREEN (-3600 -2874);
DISPLAY INVISIBLE (-3600 -2874);
FORCEPROP 0 LAST ROOM TPM
J 0
(-4000 -2725);
DISPLAY 1.021277 (-4000 -2725);
PAINT ORANGE (-4000 -2725);
DISPLAY INVISIBLE (-4000 -2725);
FORCEADD RES..1
(-4750 -3175);
FORCEPROP 1 LAST LOCATION R8E9
J 0
(-4800 -3125);
DISPLAY 0.617021 (-4800 -3125);
PAINT AQUA (-4800 -3125);
FORCEPROP 1 LAST PART_NUMBER G21796-074
J 0
(-5275 -3225);
DISPLAY 0.617021 (-5275 -3225);
PAINT BLUE (-5275 -3225);
FORCEPROP 1 LAST VALUE 33.2
J 2
(-4800 -3225);
DISPLAY 0.617021 (-4800 -3225);
PAINT SKYBLUE (-4800 -3225);
FORCEPROP 1 LAST TOLERANCE 1%
J 0
(-4675 -3225);
DISPLAY 0.617021 (-4675 -3225);
PAINT SKYBLUE (-4675 -3225);
FORCEPROP 1 LAST PACK_TYPE 0402
J 0
(-4375 -3225);
DISPLAY 0.617021 (-4375 -3225);
PAINT SKYBLUE (-4375 -3225);
FORCEPROP 1 LAST WATTAGE 1/16W
J 2
(-4875 -3225);
DISPLAY 0.617021 (-4875 -3225);
PAINT SKYBLUE (-4875 -3225);
FORCEPROP 1 LASTPIN (-4850 -3175) $PN 1
J 0
(-4838 -3163);
DISPLAY 0.617021 (-4838 -3163);
PAINT ORANGE (-4838 -3163);
FORCEPROP 1 LASTPIN (-4650 -3175) $PN 2
J 0
(-4688 -3163);
DISPLAY 0.617021 (-4688 -3163);
PAINT ORANGE (-4688 -3163);
FORCEPROP 1 LAST MATERIAL CHIP
J 0
(-4525 -3225);
DISPLAY 0.617021 (-4525 -3225);
PAINT SKYBLUE (-4525 -3225);
FORCEPROP 2 LAST CDS_LOCATION R8E9
J 0
(-4800 -3125);
DISPLAY 0.617021 (-4800 -3125);
PAINT AQUA (-4800 -3125);
DISPLAY INVISIBLE (-4800 -3125);
FORCEPROP 2 LAST SEC 1
J 0
(-4800 -2975);
DISPLAY 0.680851 (-4800 -2975);
PAINT MONO (-4800 -2975);
DISPLAY INVISIBLE (-4800 -2975);
FORCEPROP 0 LAST BOM_COST MIO_SECURITY
J 0
(-4800 -2875);
DISPLAY 1.021277 (-4800 -2875);
PAINT ORANGE (-4800 -2875);
DISPLAY INVISIBLE (-4800 -2875);
FORCEPROP 2 LAST CDS_LIB mstr_discrete
J 0
(-4750 -3175);
PAINT ORANGE (-4750 -3175);
DISPLAY INVISIBLE (-4750 -3175);
FORCEPROP 2 LAST SEC_TYPE 0402
J 0
(-4800 -2975);
DISPLAY 1.021277 (-4800 -2975);
PAINT ORANGE (-4800 -2975);
DISPLAY INVISIBLE (-4800 -2975);
FORCEPROP 1 LAST PATH I88
J 0
(-4800 -3025);
DISPLAY 0.978723 (-4800 -3025);
PAINT WHITE (-4800 -3025);
DISPLAY INVISIBLE (-4800 -3025);
FORCEPROP 0 LAST ROOM TPM
J 0
(-4800 -2975);
DISPLAY 1.021277 (-4800 -2975);
PAINT ORANGE (-4800 -2975);
DISPLAY INVISIBLE (-4800 -2975);
FORCEADD OFFPAGE..1
(-5300 -3175);
FORCEPROP 2 LAST $XR0 121 
J 0
(-5582 -3175);
DISPLAY 0.638298 (-5582 -3175);
PAINT MONO (-5582 -3175);
FORCEPROP 2 LAST $XR1 154 
J 0
(-5702 -3175);
DISPLAY 0.638298 (-5702 -3175);
PAINT MONO (-5702 -3175);
FORCEPROP 2 LAST CDS_LIB mstr_standard
J 0
(-5300 -3175);
PAINT ORANGE (-5300 -3175);
DISPLAY INVISIBLE (-5300 -3175);
FORCEPROP 2 LAST PATH I89
J 0
(-5550 -3125);
DISPLAY 1.021277 (-5550 -3125);
PAINT ORANGE (-5550 -3125);
DISPLAY INVISIBLE (-5550 -3125);
FORCEPROP 1 LAST OFFPAGE TRUE
J 0
(-4975 -3300);
DISPLAY 0.872340 (-4975 -3300);
PAINT GREEN (-4975 -3300);
DISPLAY INVISIBLE (-4975 -3300);
FORCEPROP 1 LAST COMMENT_BODY TRUE
J 0
(-5175 -3275);
DISPLAY 0.872340 (-5175 -3275);
PAINT GREEN (-5175 -3275);
DISPLAY INVISIBLE (-5175 -3275);
FORCEADD OFFPAGE..1
(-5300 -3275);
FORCEPROP 2 LAST $XR1 134 
J 0
(-5702 -3275);
DISPLAY 0.638298 (-5702 -3275);
PAINT MONO (-5702 -3275);
FORCEPROP 2 LAST $XR2 145 
J 0
(-5822 -3275);
DISPLAY 0.638298 (-5822 -3275);
PAINT MONO (-5822 -3275);
FORCEPROP 2 LAST $XR3 146 
J 0
(-5942 -3275);
DISPLAY 0.638298 (-5942 -3275);
PAINT MONO (-5942 -3275);
FORCEPROP 2 LAST $XR0 191 
J 0
(-5582 -3275);
DISPLAY 0.638298 (-5582 -3275);
PAINT MONO (-5582 -3275);
FORCEPROP 2 LAST CDS_LIB mstr_standard
J 0
(-5300 -3275);
PAINT ORANGE (-5300 -3275);
DISPLAY INVISIBLE (-5300 -3275);
FORCEPROP 2 LAST PATH I90
J 0
(-5550 -3225);
DISPLAY 1.021277 (-5550 -3225);
PAINT ORANGE (-5550 -3225);
DISPLAY INVISIBLE (-5550 -3225);
FORCEPROP 1 LAST OFFPAGE TRUE
J 0
(-4975 -3400);
DISPLAY 0.872340 (-4975 -3400);
PAINT GREEN (-4975 -3400);
DISPLAY INVISIBLE (-4975 -3400);
FORCEPROP 1 LAST COMMENT_BODY TRUE
J 0
(-5175 -3375);
DISPLAY 0.872340 (-5175 -3375);
PAINT GREEN (-5175 -3375);
DISPLAY INVISIBLE (-5175 -3375);
FORCEADD OFFPAGE..1
(-5300 -3575);
FORCEPROP 2 LAST $XR0 121 
J 0
(-5582 -3575);
DISPLAY 0.638298 (-5582 -3575);
PAINT MONO (-5582 -3575);
FORCEPROP 2 LAST CDS_LIB mstr_standard
J 0
(-5300 -3575);
PAINT ORANGE (-5300 -3575);
DISPLAY INVISIBLE (-5300 -3575);
FORCEPROP 2 LAST PATH I91
J 0
(-5550 -3525);
DISPLAY 1.021277 (-5550 -3525);
PAINT ORANGE (-5550 -3525);
DISPLAY INVISIBLE (-5550 -3525);
FORCEPROP 1 LAST OFFPAGE TRUE
J 0
(-4975 -3700);
DISPLAY 0.872340 (-4975 -3700);
PAINT GREEN (-4975 -3700);
DISPLAY INVISIBLE (-4975 -3700);
FORCEPROP 1 LAST COMMENT_BODY TRUE
J 0
(-5175 -3675);
DISPLAY 0.872340 (-5175 -3675);
PAINT GREEN (-5175 -3675);
DISPLAY INVISIBLE (-5175 -3675);
FORCEADD RES..1
(-4750 -3575);
FORCEPROP 1 LAST LOCATION R8D35
J 0
(-4800 -3525);
DISPLAY 0.617021 (-4800 -3525);
PAINT AQUA (-4800 -3525);
FORCEPROP 1 LAST VALUE 0.0
J 2
(-4800 -3625);
DISPLAY 0.617021 (-4800 -3625);
PAINT SKYBLUE (-4800 -3625);
FORCEPROP 1 LAST TOLERANCE 5%
J 0
(-4675 -3625);
DISPLAY 0.617021 (-4675 -3625);
PAINT SKYBLUE (-4675 -3625);
FORCEPROP 1 LAST PACK_TYPE 0402
J 0
(-4375 -3625);
DISPLAY 0.617021 (-4375 -3625);
PAINT SKYBLUE (-4375 -3625);
FORCEPROP 1 LAST MATERIAL CHIP
J 0
(-4525 -3625);
DISPLAY 0.617021 (-4525 -3625);
PAINT SKYBLUE (-4525 -3625);
FORCEPROP 1 LASTPIN (-4850 -3575) $PN 1
J 0
(-4838 -3563);
DISPLAY 0.617021 (-4838 -3563);
PAINT ORANGE (-4838 -3563);
FORCEPROP 1 LASTPIN (-4650 -3575) $PN 2
J 0
(-4688 -3563);
DISPLAY 0.617021 (-4688 -3563);
PAINT ORANGE (-4688 -3563);
FORCEPROP 1 LAST WATTAGE 1/16W
J 2
(-4875 -3625);
DISPLAY 0.617021 (-4875 -3625);
PAINT SKYBLUE (-4875 -3625);
FORCEPROP 1 LAST PART_NUMBER G21497-005
J 0
(-5275 -3625);
DISPLAY 0.617021 (-5275 -3625);
PAINT BLUE (-5275 -3625);
FORCEPROP 2 LAST CDS_LOCATION R8D35
J 0
(-4800 -3525);
DISPLAY 0.617021 (-4800 -3525);
PAINT AQUA (-4800 -3525);
DISPLAY INVISIBLE (-4800 -3525);
FORCEPROP 2 LAST SEC 1
J 0
(-4800 -3375);
DISPLAY 0.680851 (-4800 -3375);
PAINT MONO (-4800 -3375);
DISPLAY INVISIBLE (-4800 -3375);
FORCEPROP 2 LAST SEC_TYPE 0402
J 0
(-4800 -3375);
DISPLAY 1.021277 (-4800 -3375);
PAINT ORANGE (-4800 -3375);
DISPLAY INVISIBLE (-4800 -3375);
FORCEPROP 2 LAST CDS_LIB mstr_discrete
J 0
(-4750 -3575);
PAINT ORANGE (-4750 -3575);
DISPLAY INVISIBLE (-4750 -3575);
FORCEPROP 0 LAST BOM_COST MIO_SECURITY
J 0
(-4800 -3275);
DISPLAY 1.021277 (-4800 -3275);
PAINT ORANGE (-4800 -3275);
DISPLAY INVISIBLE (-4800 -3275);
FORCEPROP 1 LAST PATH I92
J 0
(-4800 -3425);
DISPLAY 0.978723 (-4800 -3425);
PAINT WHITE (-4800 -3425);
DISPLAY INVISIBLE (-4800 -3425);
FORCEPROP 0 LAST ROOM TPM
J 0
(-4800 -3375);
DISPLAY 1.021277 (-4800 -3375);
PAINT ORANGE (-4800 -3375);
DISPLAY INVISIBLE (-4800 -3375);
FORCEADD RES..1
(-4725 -3475);
FORCEPROP 1 LAST LOCATION R8E13
J 0
(-4775 -3425);
DISPLAY 0.617021 (-4775 -3425);
PAINT AQUA (-4775 -3425);
FORCEPROP 1 LAST VALUE 33.2
J 2
(-4800 -3525);
DISPLAY 0.617021 (-4800 -3525);
PAINT SKYBLUE (-4800 -3525);
FORCEPROP 1 LAST TOLERANCE 1%
J 0
(-4650 -3525);
DISPLAY 0.617021 (-4650 -3525);
PAINT SKYBLUE (-4650 -3525);
FORCEPROP 1 LAST PACK_TYPE 0402
J 0
(-4350 -3525);
DISPLAY 0.617021 (-4350 -3525);
PAINT SKYBLUE (-4350 -3525);
FORCEPROP 1 LAST MATERIAL CHIP
J 0
(-4500 -3525);
DISPLAY 0.617021 (-4500 -3525);
PAINT SKYBLUE (-4500 -3525);
FORCEPROP 1 LAST WATTAGE 1/16W
J 2
(-4875 -3525);
DISPLAY 0.617021 (-4875 -3525);
PAINT SKYBLUE (-4875 -3525);
FORCEPROP 1 LASTPIN (-4825 -3475) $PN 1
J 0
(-4813 -3463);
DISPLAY 0.617021 (-4813 -3463);
PAINT ORANGE (-4813 -3463);
FORCEPROP 1 LASTPIN (-4625 -3475) $PN 2
J 0
(-4663 -3463);
DISPLAY 0.617021 (-4663 -3463);
PAINT ORANGE (-4663 -3463);
FORCEPROP 1 LAST PART_NUMBER G21796-074
J 0
(-5250 -3525);
DISPLAY 0.617021 (-5250 -3525);
PAINT BLUE (-5250 -3525);
FORCEPROP 2 LAST CDS_LOCATION R8E13
J 0
(-4775 -3425);
DISPLAY 0.617021 (-4775 -3425);
PAINT AQUA (-4775 -3425);
DISPLAY INVISIBLE (-4775 -3425);
FORCEPROP 2 LAST SEC 1
J 0
(-4775 -3275);
DISPLAY 0.680851 (-4775 -3275);
PAINT MONO (-4775 -3275);
DISPLAY INVISIBLE (-4775 -3275);
FORCEPROP 2 LAST CDS_LIB mstr_discrete
J 0
(-4725 -3475);
PAINT ORANGE (-4725 -3475);
DISPLAY INVISIBLE (-4725 -3475);
FORCEPROP 0 LAST BOM_COST MIO_SECURITY
J 0
(-4775 -3175);
DISPLAY 1.021277 (-4775 -3175);
PAINT ORANGE (-4775 -3175);
DISPLAY INVISIBLE (-4775 -3175);
FORCEPROP 2 LAST SEC_TYPE 0402
J 0
(-4775 -3275);
DISPLAY 1.021277 (-4775 -3275);
PAINT ORANGE (-4775 -3275);
DISPLAY INVISIBLE (-4775 -3275);
FORCEPROP 1 LAST PATH I93
J 0
(-4775 -3325);
DISPLAY 0.978723 (-4775 -3325);
PAINT WHITE (-4775 -3325);
DISPLAY INVISIBLE (-4775 -3325);
FORCEPROP 0 LAST ROOM TPM
J 0
(-4775 -3275);
DISPLAY 1.021277 (-4775 -3275);
PAINT ORANGE (-4775 -3275);
DISPLAY INVISIBLE (-4775 -3275);
FORCEADD OFFPAGE..5
(-5300 -3475);
FORCEPROP 2 LAST $XR0 154 
J 0
(-5555 -3475);
DISPLAY 0.638298 (-5555 -3475);
PAINT MONO (-5555 -3475);
FORCEPROP 2 LAST $XR1 121 
J 0
(-5675 -3475);
DISPLAY 0.638298 (-5675 -3475);
PAINT MONO (-5675 -3475);
FORCEPROP 2 LAST CDS_LIB mstr_standard
J 0
(-5300 -3475);
PAINT ORANGE (-5300 -3475);
DISPLAY INVISIBLE (-5300 -3475);
FORCEPROP 2 LAST PATH I94
J 0
(-5550 -3425);
DISPLAY 1.021277 (-5550 -3425);
PAINT ORANGE (-5550 -3425);
DISPLAY INVISIBLE (-5550 -3425);
FORCEPROP 1 LAST OFFPAGE TRUE
J 0
(-4975 -3600);
DISPLAY 0.872340 (-4975 -3600);
PAINT GREEN (-4975 -3600);
DISPLAY INVISIBLE (-4975 -3600);
FORCEPROP 1 LAST COMMENT_BODY TRUE
J 0
(-5200 -3550);
DISPLAY 0.872340 (-5200 -3550);
PAINT GREEN (-5200 -3550);
DISPLAY INVISIBLE (-5200 -3550);
FORCEADD RES..1
(-4725 -3375);
FORCEPROP 1 LAST LOCATION R8E10
J 0
(-4775 -3325);
DISPLAY 0.617021 (-4775 -3325);
PAINT AQUA (-4775 -3325);
FORCEPROP 1 LAST VALUE 33.2
J 2
(-4775 -3425);
DISPLAY 0.617021 (-4775 -3425);
PAINT SKYBLUE (-4775 -3425);
FORCEPROP 1 LAST TOLERANCE 1%
J 0
(-4650 -3425);
DISPLAY 0.617021 (-4650 -3425);
PAINT SKYBLUE (-4650 -3425);
FORCEPROP 1 LAST PACK_TYPE 0402
J 0
(-4350 -3425);
DISPLAY 0.617021 (-4350 -3425);
PAINT SKYBLUE (-4350 -3425);
FORCEPROP 1 LAST MATERIAL CHIP
J 0
(-4500 -3425);
DISPLAY 0.617021 (-4500 -3425);
PAINT SKYBLUE (-4500 -3425);
FORCEPROP 1 LAST WATTAGE 1/16W
J 2
(-4850 -3425);
DISPLAY 0.617021 (-4850 -3425);
PAINT SKYBLUE (-4850 -3425);
FORCEPROP 1 LASTPIN (-4825 -3375) $PN 1
J 0
(-4813 -3363);
DISPLAY 0.617021 (-4813 -3363);
PAINT ORANGE (-4813 -3363);
FORCEPROP 1 LASTPIN (-4625 -3375) $PN 2
J 0
(-4663 -3363);
DISPLAY 0.617021 (-4663 -3363);
PAINT ORANGE (-4663 -3363);
FORCEPROP 1 LAST PART_NUMBER G21796-074
J 0
(-5250 -3425);
DISPLAY 0.617021 (-5250 -3425);
PAINT BLUE (-5250 -3425);
FORCEPROP 2 LAST CDS_LOCATION R8E10
J 0
(-4775 -3325);
DISPLAY 0.617021 (-4775 -3325);
PAINT AQUA (-4775 -3325);
DISPLAY INVISIBLE (-4775 -3325);
FORCEPROP 2 LAST SEC 1
J 0
(-4775 -3175);
DISPLAY 0.680851 (-4775 -3175);
PAINT MONO (-4775 -3175);
DISPLAY INVISIBLE (-4775 -3175);
FORCEPROP 0 LAST BOM_COST MIO_SECURITY
J 0
(-4775 -3075);
DISPLAY 1.021277 (-4775 -3075);
PAINT ORANGE (-4775 -3075);
DISPLAY INVISIBLE (-4775 -3075);
FORCEPROP 2 LAST CDS_LIB mstr_discrete
J 0
(-4725 -3375);
PAINT ORANGE (-4725 -3375);
DISPLAY INVISIBLE (-4725 -3375);
FORCEPROP 2 LAST SEC_TYPE 0402
J 0
(-4775 -3175);
DISPLAY 1.021277 (-4775 -3175);
PAINT ORANGE (-4775 -3175);
DISPLAY INVISIBLE (-4775 -3175);
FORCEPROP 1 LAST PATH I95
J 0
(-4775 -3225);
DISPLAY 0.978723 (-4775 -3225);
PAINT WHITE (-4775 -3225);
DISPLAY INVISIBLE (-4775 -3225);
FORCEPROP 0 LAST ROOM TPM
J 0
(-4775 -3175);
DISPLAY 1.021277 (-4775 -3175);
PAINT ORANGE (-4775 -3175);
DISPLAY INVISIBLE (-4775 -3175);
FORCEADD OFFPAGE..1
(-5300 -3375);
FORCEPROP 2 LAST $XR0 111 
J 0
(-5582 -3375);
DISPLAY 0.638298 (-5582 -3375);
PAINT MONO (-5582 -3375);
FORCEPROP 2 LAST $XR1 121 
J 0
(-5702 -3375);
DISPLAY 0.638298 (-5702 -3375);
PAINT MONO (-5702 -3375);
FORCEPROP 2 LAST $XR2 125 
J 0
(-5822 -3375);
DISPLAY 0.638298 (-5822 -3375);
PAINT MONO (-5822 -3375);
FORCEPROP 2 LAST $XR3 154 
J 0
(-5942 -3375);
DISPLAY 0.638298 (-5942 -3375);
PAINT MONO (-5942 -3375);
FORCEPROP 2 LAST CDS_LIB mstr_standard
J 0
(-5300 -3375);
PAINT ORANGE (-5300 -3375);
DISPLAY INVISIBLE (-5300 -3375);
FORCEPROP 2 LAST PATH I96
J 0
(-5550 -3325);
DISPLAY 1.021277 (-5550 -3325);
PAINT ORANGE (-5550 -3325);
DISPLAY INVISIBLE (-5550 -3325);
FORCEPROP 1 LAST OFFPAGE TRUE
J 0
(-4975 -3500);
DISPLAY 0.872340 (-4975 -3500);
PAINT GREEN (-4975 -3500);
DISPLAY INVISIBLE (-4975 -3500);
FORCEPROP 1 LAST COMMENT_BODY TRUE
J 0
(-5175 -3475);
DISPLAY 0.872340 (-5175 -3475);
PAINT GREEN (-5175 -3475);
DISPLAY INVISIBLE (-5175 -3475);
FORCEADD P3V3_STBY..1
(-3050 -2900);
FORCEPROP 3 LASTPIN (-3050 -2950) SIG_NAME P3V3_STBY\g
J 0
(-3040 -2940);
DISPLAY 0.659574 (-3040 -2940);
PAINT MONO (-3040 -2940);
DISPLAY INVISIBLE (-3040 -2940);
FORCEPROP 1 LAST VOLTAGE 3.3V
J 0
(-3095 -2943);
DISPLAY 0.340426 (-3095 -2943);
PAINT SKYBLUE (-3095 -2943);
DISPLAY INVISIBLE (-3095 -2943);
FORCEPROP 1 LAST SIZE 1B
J 0
(-3005 -2878);
DISPLAY 0.340426 (-3005 -2878);
PAINT GREEN (-3005 -2878);
DISPLAY INVISIBLE (-3005 -2878);
FORCEPROP 2 LAST CDS_LIB mstr_symbols
J 0
(-3050 -2900);
PAINT MONO (-3050 -2900);
DISPLAY INVISIBLE (-3050 -2900);
FORCEPROP 1 LAST PATH I97
J 0
(-3005 -2898);
DISPLAY 0.340426 (-3005 -2898);
PAINT GREEN (-3005 -2898);
DISPLAY INVISIBLE (-3005 -2898);
FORCEPROP 1 LAST BODY_TYPE PLUMBING
J 0
(-3095 -2943);
DISPLAY 0.340426 (-3095 -2943);
PAINT GREEN (-3095 -2943);
DISPLAY INVISIBLE (-3095 -2943);
FORCEPROP 1 LAST HDL_POWER P3V3_STBY
J 0
(-3350 -3025);
DISPLAY 0.872340 (-3350 -3025);
PAINT ORANGE (-3350 -3025);
DISPLAY INVISIBLE (-3350 -3025);
FORCEADD OFFPAGE..2
(-1750 -3325);
FORCEPROP 2 LAST $XR0 157 
J 0
(-1561 -3325);
DISPLAY 0.638298 (-1561 -3325);
PAINT MONO (-1561 -3325);
FORCEPROP 2 LAST $XR1 249 
J 0
(-1441 -3325);
DISPLAY 0.638298 (-1441 -3325);
PAINT MONO (-1441 -3325);
FORCEPROP 2 LAST $XR2 ?
J 0
(-1366 -3325);
DISPLAY 0.638298 (-1366 -3325);
PAINT MONO (-1366 -3325);
FORCEPROP 2 LAST CDS_LIB mstr_standard
J 0
(-1750 -3325);
PAINT MONO (-1750 -3325);
DISPLAY INVISIBLE (-1750 -3325);
FORCEPROP 2 LAST PATH I98
J 0
(-1700 -3250);
DISPLAY 1.021277 (-1700 -3250);
PAINT ORANGE (-1700 -3250);
DISPLAY INVISIBLE (-1700 -3250);
FORCEPROP 1 LAST OFFPAGE TRUE
J 0
(-1425 -3450);
DISPLAY 0.872340 (-1425 -3450);
PAINT GREEN (-1425 -3450);
DISPLAY INVISIBLE (-1425 -3450);
FORCEPROP 1 LAST COMMENT_BODY TRUE
J 0
(-1795 -3420);
DISPLAY 0.872340 (-1795 -3420);
PAINT GREEN (-1795 -3420);
DISPLAY INVISIBLE (-1795 -3420);
FORCEADD RES..1
(-2575 -3425);
FORCEPROP 1 LAST LOCATION R8E1
J 0
(-2625 -3375);
DISPLAY 0.617021 (-2625 -3375);
PAINT AQUA (-2625 -3375);
FORCEPROP 1 LASTPIN (-2475 -3425) $PN 2
J 0
(-2513 -3413);
DISPLAY 0.617021 (-2513 -3413);
PAINT ORANGE (-2513 -3413);
FORCEPROP 1 LAST MATERIAL CHIP
J 0
(-2350 -3475);
DISPLAY 0.617021 (-2350 -3475);
PAINT SKYBLUE (-2350 -3475);
FORCEPROP 1 LAST TOLERANCE 5%
J 0
(-2500 -3475);
DISPLAY 0.617021 (-2500 -3475);
PAINT SKYBLUE (-2500 -3475);
FORCEPROP 1 LAST WATTAGE 1/16W
J 2
(-2700 -3475);
DISPLAY 0.617021 (-2700 -3475);
PAINT SKYBLUE (-2700 -3475);
FORCEPROP 1 LASTPIN (-2675 -3425) $PN 1
J 0
(-2663 -3413);
DISPLAY 0.617021 (-2663 -3413);
PAINT ORANGE (-2663 -3413);
FORCEPROP 1 LAST PACK_TYPE 0402
J 0
(-2200 -3475);
DISPLAY 0.617021 (-2200 -3475);
PAINT SKYBLUE (-2200 -3475);
FORCEPROP 1 LAST VALUE 0.0
J 2
(-2625 -3475);
DISPLAY 0.617021 (-2625 -3475);
PAINT SKYBLUE (-2625 -3475);
FORCEPROP 1 LAST PART_NUMBER G21497-005
J 0
(-3100 -3475);
DISPLAY 0.617021 (-3100 -3475);
PAINT BLUE (-3100 -3475);
FORCEPROP 2 LAST CDS_LOCATION R8E1
J 0
(-2625 -3375);
DISPLAY 0.617021 (-2625 -3375);
PAINT AQUA (-2625 -3375);
DISPLAY INVISIBLE (-2625 -3375);
FORCEPROP 2 LAST $SEC 1
J 0
(-2625 -3225);
DISPLAY 0.680851 (-2625 -3225);
PAINT MONO (-2625 -3225);
DISPLAY INVISIBLE (-2625 -3225);
FORCEPROP 2 LAST CDS_SEC 1
J 0
(-2625 -3225);
DISPLAY 1.021277 (-2625 -3225);
PAINT ORANGE (-2625 -3225);
DISPLAY INVISIBLE (-2625 -3225);
FORCEPROP 0 LAST BOM_COST MIO_SECURITY
J 0
(-2625 -3125);
DISPLAY 1.021277 (-2625 -3125);
PAINT ORANGE (-2625 -3125);
DISPLAY INVISIBLE (-2625 -3125);
FORCEPROP 2 LAST CDS_LIB mstr_discrete
J 0
(-2575 -3425);
PAINT ORANGE (-2575 -3425);
DISPLAY INVISIBLE (-2575 -3425);
FORCEPROP 1 LAST PATH I99
J 0
(-2625 -3275);
DISPLAY 0.978723 (-2625 -3275);
PAINT WHITE (-2625 -3275);
DISPLAY INVISIBLE (-2625 -3275);
FORCEPROP 0 LAST ROOM TPM
J 0
(-2625 -3225);
DISPLAY 1.021277 (-2625 -3225);
PAINT ORANGE (-2625 -3225);
DISPLAY INVISIBLE (-2625 -3225);
FORCEADD CAD_NOTE..1
(-5425 -4025);
FORCEPROP 0 LAST L1 PLACE R8E9 WITHIN 200 MILS OF SPI_PCH_CLK T-POINT AND WITH 500 MILS OF TPM CONN
J 0
(-5575 -4150);
DISPLAY 1.021277 (-5575 -4150);
PAINT ORANGE (-5575 -4150);
FORCEPROP 0 LAST L2 PLACE R8E13 NEAR TPM CONN
J 0
(-5575 -4225);
DISPLAY 1.021277 (-5575 -4225);
PAINT ORANGE (-5575 -4225);
FORCEPROP 0 LAST L3 PLACE R8E10 NEAR TPM CONN
J 0
(-5575 -4300);
DISPLAY 1.021277 (-5575 -4300);
PAINT ORANGE (-5575 -4300);
FORCEPROP 2 LAST CDS_LIB mstr_symbols
J 0
(-5425 -4025);
PAINT ORANGE (-5425 -4025);
DISPLAY INVISIBLE (-5425 -4025);
FORCEPROP 1 LAST COMMENT_BODY TRUE
J 0
(-5400 -3925);
DISPLAY 0.978723 (-5400 -3925);
PAINT ORANGE (-5400 -3925);
DISPLAY INVISIBLE (-5400 -3925);
FORCEADD INTEL_CORP_BPAGE..1
(350 -5900);
FORCEPROP 1 LAST CDS_CON_LAST_MODIFIED Tue Dec 01 11:52:16 2015
J 0
(-1075 -5575);
DISPLAY 1.361702 (-1075 -5575);
PAINT GREEN (-1075 -5575);
DISPLAY INVISIBLE (-1075 -5575);
FORCEPROP 1 LAST CUSTOM_TXT_CDS <CURRENT_DESIGN_SHEET> OF <TOTAL_DESIGN_SHEETS>
J 0
(-150 -5875);
PAINT GREEN (-150 -5875);
FORCEPROP 2 LAST CUSTOM_TXT_CDS <XR_PAGE_TITLE>
J 0
(-7540 -650);
DISPLAY 0.638298 (-7540 -650);
PAINT PINK (-7540 -650);
DISPLAY INVISIBLE (-7540 -650);
FORCEPROP 2 LAST CUSTOM_TXT_CDS <CON_LAST_MODIFIED>
J 0
(-1575 -5550);
DISPLAY 1.361702 (-1575 -5550);
PAINT GREEN (-1575 -5550);
FORCEPROP 1 LAST SCH_ADDRESS3 Santa Clara, CA 95052-8119
J 0
(-3625 -5875);
DISPLAY 0.617021 (-3625 -5875);
PAINT GREEN (-3625 -5875);
FORCEPROP 1 LAST SCH_ADDRESS2 P.O. BOX 58119
J 0
(-3625 -5825);
DISPLAY 0.617021 (-3625 -5825);
PAINT GREEN (-3625 -5825);
FORCEPROP 1 LAST SCH_ADDRESS1 2200 Mission College Blvd.
J 0
(-3625 -5775);
DISPLAY 0.617021 (-3625 -5775);
PAINT GREEN (-3625 -5775);
FORCEPROP 1 LAST SCH_TITLE SPI TPM CONNECTOR
J 0
(-7600 -5850);
DISPLAY 1.212766 (-7600 -5850);
PAINT ORANGE (-7600 -5850);
FORCEPROP 1 LAST SCH_NUMBER H4694802
J 0
(-950 -5750);
DISPLAY 1.212766 (-950 -5750);
PAINT YELLOW (-950 -5750);
FORCEPROP 1 LAST SCH_DEPT BESD
J 1
(-4100 -5800);
DISPLAY 1.212766 (-4100 -5800);
PAINT YELLOW (-4100 -5800);
FORCEPROP 1 LAST SCH_REV 2.420
J 0
(100 -5750);
DISPLAY 0.978723 (100 -5750);
PAINT YELLOW (100 -5750);
FORCEPROP 2 LAST CDS_LIB mstr_symbols
J 0
(350 -5900);
DISPLAY 1.361702 (350 -5900);
PAINT ORANGE (350 -5900);
DISPLAY INVISIBLE (350 -5900);
FORCEPROP 2 LAST PAGE_BORDER TRUE
J 0
(-7540 -650);
DISPLAY 0.872340 (-7540 -650);
PAINT PINK (-7540 -650);
DISPLAY INVISIBLE (-7540 -650);
FORCEPROP 1 LAST COMMENT_BODY TRUE
J 0
(362 -5888);
DISPLAY 0.617021 (362 -5888);
PAINT GREEN (362 -5888);
DISPLAY INVISIBLE (362 -5888);
FORCEPROP 2 LAST CDS_XR_PAGE_TITLE CR-184 : @BASEBOARD_FAB2_LIB.BASEBOARD_FAB2(SCH_1):PAGE184
J 0
(-7540 -650);
DISPLAY 0.638298 (-7540 -650);
PAINT PINK (-7540 -650);
DISPLAY INVISIBLE (-7540 -650);
WIRE 16 -1 (-3225 -3125)(-3350 -3125);
WIRE 16 -1 (-3225 -3625)(-3225 -3125);
WIRE 16 -1 (-3225 -3725)(-3225 -3625);
WIRE 16 -1 (-3225 -3625)(-3350 -3625);
WIRE 16 -1 (-3225 -3850)(-3225 -3725);
WIRE 16 -1 (-3225 -3725)(-3350 -3725);
WIRE 16 -1 (-4850 -1900)(-4975 -1900);
WIRE 16 -1 (-4850 -2075)(-4850 -1900);
WIRE 16 -1 (-3050 -2950)(-3050 -3225);
WIRE 16 -1 (-3050 -3225)(-3350 -3225);
WIRE 16 -1 (-5250 -3575)(-4850 -3575);
FORCEPROP 2 LAST SIG_NAME SPI_PCH_TPM_CS_N
J 0
(-5250 -3565);
DISPLAY 0.617021 (-5250 -3565);
PAINT ORANGE (-5250 -3565);
WIRE 16 -1 (-5250 -3475)(-4825 -3475);
FORCEPROP 2 LAST SIG_NAME SPI_PCH_MISO
J 0
(-5250 -3465);
DISPLAY 0.617021 (-5250 -3465);
PAINT ORANGE (-5250 -3465);
WIRE 3 2175 (-3600 -3375)(-1250 -3375);
WIRE 3 2175 (-3600 -3275)(-3600 -3375);
WIRE 3 2175 (-1250 -3275)(-1250 -3375);
WIRE 3 2175 (-3600 -3275)(-1250 -3275);
WIRE 16 -1 (-1800 -3525)(-3350 -3525);
FORCEPROP 0 LAST SIG_NAME SMB_SENSOR_STBY_LVC3_SCL
J 0
(-3130 -3515);
DISPLAY 0.617021 (-3130 -3515);
PAINT ORANGE (-3130 -3515);
WIRE 16 -1 (-3350 -3425)(-2675 -3425);
FORCEPROP 2 LAST SIG_NAME IRQ_SPI_TPM_N_R
J 0
(-3135 -3425);
DISPLAY 0.617021 (-3135 -3425);
PAINT ORANGE (-3135 -3425);
FORCEPROP 2 LASTPROP $XRERR UNIQUE?
J 0
(-3375 -3425);
DISPLAY 0.638298 (-3375 -3425);
PAINT MONO (-3375 -3425);
DISPLAY INVISIBLE (-3375 -3425);
WIRE 16 -1 (-3350 -3325)(-1800 -3325);
FORCEPROP 0 LAST SIG_NAME FM_TPM_PRES_RST_N
J 0
(-2910 -3315);
DISPLAY 0.680851 (-2910 -3315);
PAINT ORANGE (-2910 -3315);
WIRE 16 -1 (-2475 -3425)(-1800 -3425);
FORCEPROP 2 LAST SIG_NAME IRQ_PIRQA_SPI_TPM_N
J 0
(-2435 -3415);
DISPLAY 0.617021 (-2435 -3415);
PAINT ORANGE (-2435 -3415);
WIRE 16 -1 (-5250 -3375)(-4825 -3375);
FORCEPROP 2 LAST SIG_NAME SPI_PCH_MOSI
J 0
(-5250 -3365);
DISPLAY 0.617021 (-5250 -3365);
PAINT ORANGE (-5250 -3365);
WIRE 16 -1 (-5250 -3175)(-4850 -3175);
FORCEPROP 2 LAST SIG_NAME SPI_PCH_CLK
J 0
(-5250 -3165);
DISPLAY 0.617021 (-5250 -3165);
PAINT ORANGE (-5250 -3165);
WIRE 16 -1 (-4625 -3475)(-4050 -3475);
FORCEPROP 2 LAST SIG_NAME SPI_PCH_TPM_MISO_R
J 0
(-4625 -3465);
DISPLAY 0.617021 (-4625 -3465);
PAINT ORANGE (-4625 -3465);
FORCEPROP 2 LASTPROP $XRERR UNIQUE?
J 0
(-4865 -3465);
DISPLAY 0.638298 (-4865 -3465);
PAINT MONO (-4865 -3465);
DISPLAY INVISIBLE (-4865 -3465);
WIRE 16 -1 (-4650 -3175)(-4050 -3175);
FORCEPROP 2 LAST SIG_NAME SPI_PCH_TPM_CLK_R
J 0
(-4625 -3165);
DISPLAY 0.617021 (-4625 -3165);
PAINT ORANGE (-4625 -3165);
FORCEPROP 2 LASTPROP $XRERR UNIQUE?
J 0
(-4865 -3165);
DISPLAY 0.638298 (-4865 -3165);
PAINT MONO (-4865 -3165);
DISPLAY INVISIBLE (-4865 -3165);
WIRE 16 -1 (-4625 -3375)(-4050 -3375);
FORCEPROP 2 LAST SIG_NAME SPI_PCH_TPM_MOSI_R
J 0
(-4625 -3365);
DISPLAY 0.617021 (-4625 -3365);
PAINT ORANGE (-4625 -3365);
FORCEPROP 2 LASTPROP $XRERR UNIQUE?
J 0
(-4865 -3365);
DISPLAY 0.638298 (-4865 -3365);
PAINT MONO (-4865 -3365);
DISPLAY INVISIBLE (-4865 -3365);
WIRE 16 -1 (-4650 -3575)(-4050 -3575);
FORCEPROP 2 LAST SIG_NAME SPI_PCH_TPM_CS_R_N
J 0
(-4625 -3565);
DISPLAY 0.617021 (-4625 -3565);
PAINT ORANGE (-4625 -3565);
FORCEPROP 2 LASTPROP $XRERR UNIQUE?
J 0
(-4865 -3565);
DISPLAY 0.638298 (-4865 -3565);
PAINT MONO (-4865 -3565);
DISPLAY INVISIBLE (-4865 -3565);
WIRE 16 -1 (-5250 -3275)(-4050 -3275);
FORCEPROP 2 LAST SIG_NAME RST_PLTRST_BUF_N
J 0
(-5250 -3265);
DISPLAY 0.617021 (-5250 -3265);
PAINT ORANGE (-5250 -3265);
WIRE 16 -1 (-5250 -3675)(-4050 -3675);
FORCEPROP 0 LAST SIG_NAME SMB_SENSOR_STBY_LVC3_SDA
J 0
(-5250 -3664);
DISPLAY 0.617021 (-5250 -3664);
PAINT ORANGE (-5250 -3664);
DOT 1 (-3225 -3725);
DOT 1 (-3225 -3625);
FORCENOTE
TP FAB1 FOR BMC TPM 1120
(-2625 -3225) 0;
DISPLAY LEFT (-2625 -3225);
DISPLAY 1.021277 (-2625 -3225);
PAINT RED (-2625 -3225);
FORCENOTE
ROOM=TPM
(-7575 -5600) 0;
DISPLAY LEFT (-7575 -5600);
DISPLAY 1.021277 (-7575 -5600);
PAINT PURPLE (-7575 -5600);
FORCENOTE
BOM_COST=MIO_SECURITY
(-7550 -5675) 0;
DISPLAY LEFT (-7550 -5675);
DISPLAY 1.021277 (-7550 -5675);
PAINT PURPLE (-7550 -5675);
QUIT
